# BASEBOARD_FAB2 (Tioga Pass) — schematic netlist excerpt (pin names and nets, part order shuffled) for the footprints in the layout excerpt that follows; sources: Cadence DE-HDL packaged netlist, KiCad conversion of Wiwynn_Tioga_Pass_MB.brd

R8F26  RES  10.0K 1% CHIP  pkg 0402  page 156 : A = P3V3_STBY ; B = FM_PCH_PWRBTN_R_N
C3N36  CAP  10UF 16V 10% X6S  pkg 0805  page 212 : A = VR_FET_SW_P12V_STBY_PVCCIO_CPU0 ; B = GND
R2W2  RES  49.9 1% EMPTY  pkg 0402  page 93 : A = PVCCIO_CPU0 ; B = P0V7_GTL2104_5_VREF

(kicad_pcb
	(version 20260206)
	(generator "pcbnew")
	(generator_version "10.0")
	(general
		(thickness 1.6)
		(legacy_teardrops no)
	)
	(paper "A4")
	(title_block
		(title "Wiwynn_Tioga_Pass_MB.brd")
		(comment 1 "Tioga Pass / footprints 3400-3402 of 4770")
	)
	(layers
		(0 "F.Cu" signal "TOP")
		(4 "In1.Cu" signal "L2GND")
		(6 "In2.Cu" signal "L3")
		(8 "In3.Cu" signal "L4GND")
		(10 "In4.Cu" signal "L5")
		(12 "In5.Cu" signal "L6GND")
		(14 "In6.Cu" signal "L7VCC")
		(16 "In7.Cu" signal "L8VCC")
		(18 "In8.Cu" signal "L9GND")
		(20 "In9.Cu" signal "L10")
		(22 "In10.Cu" signal "L11GND")
		(24 "In11.Cu" signal "L12")
		(26 "In12.Cu" signal "L13GND")
		(2 "B.Cu" signal "BOTTOM")
		(9 "F.Adhes" user "F.Adhesive")
		(11 "B.Adhes" user "B.Adhesive")
		(13 "F.Paste" user "Package Geometry/Pastemask Top")
		(15 "B.Paste" user "Package Geometry/Pastemask Bottom")
		(5 "F.SilkS" user "Ref Des/Silkscreen Top")
		(7 "B.SilkS" user "Ref Des/Silkscreen Bottom")
		(1 "F.Mask" user "Board Geometry/Soldermask Top")
		(3 "B.Mask" user "Board Geometry/Soldermask Bottom")
		(17 "Dwgs.User" user "User.Drawings")
		(19 "Cmts.User" user "User.Comments")
		(21 "Eco1.User" user "User.Eco1")
		(23 "Eco2.User" user "User.Eco2")
		(25 "Edge.Cuts" user "Board Geometry/Outline")
		(27 "Margin" user)
		(31 "F.CrtYd" user "Package Geometry/Place Bound Top")
		(29 "B.CrtYd" user "Package Geometry/Place Bound Bottom")
		(35 "F.Fab" user "Ref Des/Assembly Top")
		(33 "B.Fab" user "Ref Des/Assembly Bottom")
	)
	(footprint ""
		(layer "B.Cu")
		(at 348.1578 -94.869 -90)
		(property "Reference" "C3N36"
			(at 0 0 90)
			(layer "B.SilkS")
			(hide yes)
			(effects
				(font
					(size 1.27 1.27)
				)
				(justify mirror)
			)
		)
		(property "Value" ""
			(at 0 0 90)
			(layer "B.Fab")
			(effects
				(font
					(size 1.27 1.27)
				)
				(justify mirror)
			)
		)
		(duplicate_pad_numbers_are_jumpers no)
		(fp_poly
			(pts
				(xy 0.7239 -0.2159) (xy -0.7239 -0.2159) (xy -0.7239 1.9939) (xy 0.7239 1.9939)
			)
			(stroke
				(width 0)
				(type default)
			)
			(fill no)
			(layer "B.CrtYd")
		)
		(fp_line
			(start -0.7239 1.9939)
			(end -0.7239 -0.2159)
			(stroke
				(width 0.1)
				(type default)
			)
			(layer "B.Fab")
		)
		(fp_line
			(start 0.7239 1.9939)
			(end -0.7239 1.9939)
			(stroke
				(width 0.1)
				(type default)
			)
			(layer "B.Fab")
		)
		(fp_line
			(start -0.7239 -0.2159)
			(end 0.7239 -0.2159)
			(stroke
				(width 0.1)
				(type default)
			)
			(layer "B.Fab")
		)
		(fp_line
			(start 0.7239 -0.2159)
			(end 0.7239 1.9939)
			(stroke
				(width 0.1)
				(type default)
			)
			(layer "B.Fab")
		)
		(pad "1" smd rect
			(at 0 0 90)
			(size 1.27 1.016)
			(layers "B.Cu" "B.Mask" "B.Paste")
			(net "VR_FET_SW_P12V_STBY_PVCCIO_CPU0")
		)
		(pad "2" smd rect
			(at 0 1.778 90)
			(size 1.27 1.016)
			(layers "B.Cu" "B.Mask" "B.Paste")
			(net "GND")
		)
		(zone
			(layer "B.Cu")
			(hatch none 0.5)
			(connect_pads
				(clearance 0)
			)
			(min_thickness 0.25)
			(keepout
				(tracks not_allowed)
				(vias allowed)
				(pads allowed)
				(copperpour not_allowed)
				(footprints allowed)
			)
			(placement
				(enabled no)
				(sheetname "")
			)
			(fill
				(thermal_gap 0.5)
				(thermal_bridge_width 0.5)
				(island_removal_mode 0)
			)
			(polygon
				(pts
					(xy 347.6498 -94.234) (xy 347.6498 -95.504) (xy 346.8878 -95.504) (xy 346.8878 -94.234)
				)
			)
		)
	)
	(footprint ""
		(layer "B.Cu")
		(at 396.240508 -29.845 90)
		(property "Reference" "R8F26"
			(at 0 0 90)
			(layer "B.SilkS")
			(hide yes)
			(effects
				(font
					(size 1.27 1.27)
				)
				(justify mirror)
			)
		)
		(property "Value" ""
			(at 0 0 90)
			(layer "B.Fab")
			(effects
				(font
					(size 1.27 1.27)
				)
				(justify mirror)
			)
		)
		(duplicate_pad_numbers_are_jumpers no)
		(fp_poly
			(pts
				(xy 0.2794 -0.101854) (xy -0.2794 -0.101854) (xy -0.2794 0.990346) (xy 0.2794 0.990346)
			)
			(stroke
				(width 0)
				(type default)
			)
			(fill no)
			(layer "B.CrtYd")
		)
		(fp_line
			(start 0.2794 -0.101854)
			(end 0.2794 0.990346)
			(stroke
				(width 0.1)
				(type default)
			)
			(layer "B.Fab")
		)
		(fp_line
			(start -0.2794 -0.101854)
			(end 0.2794 -0.101854)
			(stroke
				(width 0.1)
				(type default)
			)
			(layer "B.Fab")
		)
		(fp_line
			(start 0.2794 0.990346)
			(end -0.2794 0.990346)
			(stroke
				(width 0.1)
				(type default)
			)
			(layer "B.Fab")
		)
		(fp_line
			(start -0.2794 0.990346)
			(end -0.2794 -0.101854)
			(stroke
				(width 0.1)
				(type default)
			)
			(layer "B.Fab")
		)
		(pad "1" smd rect
			(at 0 0 270)
			(size 0.508 0.508)
			(layers "B.Cu" "B.Mask" "B.Paste")
			(net "P3V3_STBY")
		)
		(pad "2" smd rect
			(at 0 0.889 270)
			(size 0.508 0.508)
			(layers "B.Cu" "B.Mask" "B.Paste")
			(net "FM_PCH_PWRBTN_R_N")
		)
	)
	(footprint ""
		(layer "B.Cu")
		(at 376.9614 -45.1358)
		(property "Reference" "R2W2"
			(at 0.8382 -0.67818 0)
			(unlocked yes)
			(layer "B.SilkS")
			(effects
				(font
					(size 0.4064 0.254)
					(thickness 0.1524)
				)
				(justify left mirror)
			)
		)
		(property "Value" ""
			(at 0 0 0)
			(layer "B.Fab")
			(effects
				(font
					(size 1.27 1.27)
				)
				(justify mirror)
			)
		)
		(duplicate_pad_numbers_are_jumpers no)
		(fp_poly
			(pts
				(xy 0.2794 -0.1016) (xy -0.2794 -0.1016) (xy -0.2794 0.9906) (xy 0.2794 0.9906)
			)
			(stroke
				(width 0)
				(type default)
			)
			(fill no)
			(layer "B.CrtYd")
		)
		(fp_line
			(start -0.2794 -0.1016)
			(end 0.2794 -0.1016)
			(stroke
				(width 0.1)
				(type default)
			)
			(layer "B.Fab")
		)
		(fp_line
			(start -0.2794 0.9906)
			(end -0.2794 -0.1016)
			(stroke
				(width 0.1)
				(type default)
			)
			(layer "B.Fab")
		)
		(fp_line
			(start 0.2794 -0.1016)
			(end 0.2794 0.9906)
			(stroke
				(width 0.1)
				(type default)
			)
			(layer "B.Fab")
		)
		(fp_line
			(start 0.2794 0.9906)
			(end -0.2794 0.9906)
			(stroke
				(width 0.1)
				(type default)
			)
			(layer "B.Fab")
		)
		(pad "1" smd rect
			(at 0 0 180)
			(size 0.508 0.508)
			(layers "B.Cu" "B.Mask" "B.Paste")
			(net "PVCCIO_CPU0")
		)
		(pad "2" smd rect
			(at 0 0.889 180)
			(size 0.508 0.508)
			(layers "B.Cu" "B.Mask" "B.Paste")
			(net "P0V7_GTL2104_5_VREF")
		)
		(zone
			(layer "B.Cu")
			(hatch none 0.5)
			(connect_pads
				(clearance 0)
			)
			(min_thickness 0.25)
			(keepout
				(tracks allowed)
				(vias not_allowed)
				(pads allowed)
				(copperpour not_allowed)
				(footprints allowed)
			)
			(placement
				(enabled no)
				(sheetname "")
			)
			(fill
				(thermal_gap 0.5)
				(thermal_bridge_width 0.5)
				(island_removal_mode 0)
			)
			(polygon
				(pts
					(xy 377.2154 -44.8818) (xy 376.7074 -44.8818) (xy 376.7074 -44.5008) (xy 377.2154 -44.5008)
				)
			)
		)
		(zone
			(layer "B.Cu")
			(hatch none 0.5)
			(connect_pads
				(clearance 0)
			)
			(min_thickness 0.25)
			(keepout
				(tracks not_allowed)
				(vias allowed)
				(pads allowed)
				(copperpour not_allowed)
				(footprints allowed)
			)
			(placement
				(enabled no)
				(sheetname "")
			)
			(fill
				(thermal_gap 0.5)
				(thermal_bridge_width 0.5)
				(island_removal_mode 0)
			)
			(polygon
				(pts
					(xy 377.2154 -44.5008) (xy 376.7074 -44.5008) (xy 376.7074 -44.8818) (xy 377.2154 -44.8818)
				)
			)
		)
	)
)
